(kicad_pcb
	(version 20241229)
	(generator "pcbnew")
	(generator_version "9.0")
	(general
		(thickness 1.599998)
		(legacy_teardrops no)
	)
	(paper "A4")
	(title_block
		(title "Artix - Datacenter Secure Control Module (DC-SCM)")
		(date "2024-11-06")
		(rev "1.1.3")
		(comment 9 "footprints 272-276 of 544")
	)
	(layers
		(0 "F.Cu" signal)
		(4 "In1.Cu" signal)
		(6 "In2.Cu" signal)
		(8 "In3.Cu" signal)
		(10 "In4.Cu" signal)
		(12 "In5.Cu" signal)
		(14 "In6.Cu" signal)
		(2 "B.Cu" signal)
		(9 "F.Adhes" user "F.Adhesive")
		(11 "B.Adhes" user "B.Adhesive")
		(13 "F.Paste" user)
		(15 "B.Paste" user)
		(5 "F.SilkS" user "F.Silkscreen")
		(7 "B.SilkS" user "B.Silkscreen")
		(1 "F.Mask" user)
		(3 "B.Mask" user)
		(17 "Dwgs.User" user "User.Drawings")
		(19 "Cmts.User" user "User.Comments")
		(21 "Eco1.User" user "User.Eco1")
		(23 "Eco2.User" user "User.Eco2")
		(25 "Edge.Cuts" user)
		(27 "Margin" user)
		(31 "F.CrtYd" user "F.Courtyard")
		(29 "B.CrtYd" user "B.Courtyard")
		(35 "F.Fab" user)
		(33 "B.Fab" user)
	)
	(footprint "antmicro-footprints:C_0603_1608Metric"
		(layer "B.Cu")
		(at 114.4 131.4 180)
		(descr "Capacitor SMD 0603")
		(tags "capacitor 0603")
		(property "Reference" "C100"
			(at 1 -0.4 0)
			(layer "B.SilkS")
			(effects
				(font
					(size 0.7 0.7)
					(thickness 0.15)
				)
				(justify left bottom mirror)
			)
		)
		(property "Value" "C_4u7_0603"
			(at 0 -1.6 0)
			(layer "B.Fab")
			(effects
				(font
					(size 0.7 0.7)
					(thickness 0.15)
				)
				(justify left bottom mirror)
			)
		)
		(property "Datasheet" "https://product.tdk.com/en/search/capacitor/ceramic/mlcc/info?part_no=C1608X5R1V475M080AC"
			(at 0 0 180)
			(layer "F.Fab")
			(hide yes)
			(effects
				(font
					(size 1.27 1.27)
					(thickness 0.15)
				)
			)
		)
		(property "Description" "SMD Multilayer Ceramic Capacitor, 4.7 µF, 35 V, 0603 [1608 Metric], ± 20%, X5R, C"
			(at 0 0 180)
			(layer "F.Fab")
			(hide yes)
			(effects
				(font
					(size 1.27 1.27)
					(thickness 0.15)
				)
			)
		)
		(property "Author" "Antmicro"
			(at 228.8 262.8 0)
			(layer "B.Fab")
			(hide yes)
			(effects
				(font
					(size 1 1)
					(thickness 0.15)
				)
				(justify mirror)
			)
		)
		(property "Dielectric" ""
			(at 228.8 262.8 0)
			(layer "B.Fab")
			(hide yes)
			(effects
				(font
					(size 1 1)
					(thickness 0.15)
				)
				(justify mirror)
			)
		)
		(property "License" "Apache-2.0"
			(at 228.8 262.8 0)
			(layer "B.Fab")
			(hide yes)
			(effects
				(font
					(size 1 1)
					(thickness 0.15)
				)
				(justify mirror)
			)
		)
		(property "MPN" "C1608X5R1V475M080AC"
			(at 228.8 262.8 0)
			(layer "B.Fab")
			(hide yes)
			(effects
				(font
					(size 1 1)
					(thickness 0.15)
				)
				(justify mirror)
			)
		)
		(property "Manufacturer" "TDK"
			(at 228.8 262.8 0)
			(layer "B.Fab")
			(hide yes)
			(effects
				(font
					(size 1 1)
					(thickness 0.15)
				)
				(justify mirror)
			)
		)
		(property "Val" "4u7"
			(at 228.8 262.8 0)
			(layer "B.Fab")
			(hide yes)
			(effects
				(font
					(size 1 1)
					(thickness 0.15)
				)
				(justify mirror)
			)
		)
		(property "Voltage" ""
			(at 228.8 262.8 0)
			(layer "B.Fab")
			(hide yes)
			(effects
				(font
					(size 1 1)
					(thickness 0.15)
				)
				(justify mirror)
			)
		)
		(property "DNP" ""
			(at 0 0 180)
			(unlocked yes)
			(layer "B.Fab")
			(hide yes)
			(effects
				(font
					(size 1 1)
					(thickness 0.15)
				)
				(justify mirror)
			)
		)
		(sheetname "/FPGA banks 13-16/")
		(sheetfile "fpga-banks-13-16.kicad_sch")
		(attr smd)
		(fp_line
			(start -0.15 0.4)
			(end 0.15 0.4)
			(stroke
				(width 0.15)
				(type solid)
			)
			(layer "B.SilkS")
		)
		(fp_line
			(start -0.15 -0.4)
			(end 0.15 -0.4)
			(stroke
				(width 0.15)
				(type solid)
			)
			(layer "B.SilkS")
		)
		(fp_rect
			(start -1.25 0.65)
			(end 1.25 -0.65)
			(stroke
				(width 0.05)
				(type solid)
			)
			(fill no)
			(layer "B.CrtYd")
		)
		(fp_rect
			(start -0.8 0.4)
			(end 0.8 -0.4)
			(stroke
				(width 0.15)
				(type solid)
			)
			(fill no)
			(layer "B.Fab")
		)
		(pad "1" smd roundrect
			(at -0.7 0 180)
			(size 0.8 1)
			(layers "B.Cu" "B.Mask" "B.Paste")
			(roundrect_rratio 0.2)
			(net 1 "GND")
			(pintype "passive")
		)
		(pad "2" smd roundrect
			(at 0.7 0 180)
			(size 0.8 1)
			(layers "B.Cu" "B.Mask" "B.Paste")
			(roundrect_rratio 0.2)
			(net 2 "VCC3V3")
			(pintype "passive")
		)
	)
	(footprint "antmicro-footprints:C_0603_1608Metric"
		(layer "B.Cu")
		(at 90.5 151.5)
		(descr "Capacitor SMD 0603")
		(tags "capacitor 0603")
		(property "Reference" "C102"
			(at -3.9 0.4 0)
			(layer "B.SilkS")
			(effects
				(font
					(size 0.7 0.7)
					(thickness 0.15)
				)
				(justify right bottom mirror)
			)
		)
		(property "Value" "C_4u7_0603"
			(at 0 -1.6 0)
			(layer "B.Fab")
			(effects
				(font
					(size 0.7 0.7)
					(thickness 0.15)
				)
				(justify right bottom mirror)
			)
		)
		(property "Datasheet" "https://product.tdk.com/en/search/capacitor/ceramic/mlcc/info?part_no=C1608X5R1V475M080AC"
			(at 0 0 0)
			(layer "F.Fab")
			(hide yes)
			(effects
				(font
					(size 1.27 1.27)
					(thickness 0.15)
				)
			)
		)
		(property "Description" "SMD Multilayer Ceramic Capacitor, 4.7 µF, 35 V, 0603 [1608 Metric], ± 20%, X5R, C"
			(at 0 0 0)
			(layer "F.Fab")
			(hide yes)
			(effects
				(font
					(size 1.27 1.27)
					(thickness 0.15)
				)
			)
		)
		(property "Author" "Antmicro"
			(at 0 0 0)
			(layer "B.Fab")
			(hide yes)
			(effects
				(font
					(size 1 1)
					(thickness 0.15)
				)
				(justify mirror)
			)
		)
		(property "Dielectric" ""
			(at 0 0 0)
			(layer "B.Fab")
			(hide yes)
			(effects
				(font
					(size 1 1)
					(thickness 0.15)
				)
				(justify mirror)
			)
		)
		(property "License" "Apache-2.0"
			(at 0 0 0)
			(layer "B.Fab")
			(hide yes)
			(effects
				(font
					(size 1 1)
					(thickness 0.15)
				)
				(justify mirror)
			)
		)
		(property "MPN" "C1608X5R1V475M080AC"
			(at 0 0 0)
			(layer "B.Fab")
			(hide yes)
			(effects
				(font
					(size 1 1)
					(thickness 0.15)
				)
				(justify mirror)
			)
		)
		(property "Manufacturer" "TDK"
			(at 0 0 0)
			(layer "B.Fab")
			(hide yes)
			(effects
				(font
					(size 1 1)
					(thickness 0.15)
				)
				(justify mirror)
			)
		)
		(property "Val" "4u7"
			(at 0 0 0)
			(layer "B.Fab")
			(hide yes)
			(effects
				(font
					(size 1 1)
					(thickness 0.15)
				)
				(justify mirror)
			)
		)
		(property "Voltage" ""
			(at 0 0 0)
			(layer "B.Fab")
			(hide yes)
			(effects
				(font
					(size 1 1)
					(thickness 0.15)
				)
				(justify mirror)
			)
		)
		(sheetname "/FPGA banks 34-35 & CFG/")
		(sheetfile "fpga-banks-34-25-cfg.kicad_sch")
		(attr smd)
		(fp_line
			(start -0.15 -0.4)
			(end 0.15 -0.4)
			(stroke
				(width 0.15)
				(type solid)
			)
			(layer "B.SilkS")
		)
		(fp_line
			(start -0.15 0.4)
			(end 0.15 0.4)
			(stroke
				(width 0.15)
				(type solid)
			)
			(layer "B.SilkS")
		)
		(fp_rect
			(start -1.25 0.65)
			(end 1.25 -0.65)
			(stroke
				(width 0.05)
				(type solid)
			)
			(fill no)
			(layer "B.CrtYd")
		)
		(fp_rect
			(start -0.8 0.4)
			(end 0.8 -0.4)
			(stroke
				(width 0.15)
				(type solid)
			)
			(fill no)
			(layer "B.Fab")
		)
		(pad "1" smd roundrect
			(at -0.7 0)
			(size 0.8 1)
			(layers "B.Cu" "B.Mask" "B.Paste")
			(roundrect_rratio 0.2)
			(net 1 "GND")
			(pintype "passive")
		)
		(pad "2" smd roundrect
			(at 0.7 0)
			(size 0.8 1)
			(layers "B.Cu" "B.Mask" "B.Paste")
			(roundrect_rratio 0.2)
			(net 3 "VCC1V35")
			(pintype "passive")
		)
	)
	(footprint "antmicro-footprints:C_0603_1608Metric"
		(layer "B.Cu")
		(at 91.3 133.6 90)
		(descr "Capacitor SMD 0603")
		(tags "capacitor 0603")
		(property "Reference" "C104"
			(at -3.9 0.3 90)
			(layer "B.SilkS")
			(effects
				(font
					(size 0.7 0.7)
					(thickness 0.15)
				)
				(justify right bottom mirror)
			)
		)
		(property "Value" "C_4u7_0603"
			(at 0 -1.6 90)
			(layer "B.Fab")
			(effects
				(font
					(size 0.7 0.7)
					(thickness 0.15)
				)
				(justify right bottom mirror)
			)
		)
		(property "Datasheet" "https://product.tdk.com/en/search/capacitor/ceramic/mlcc/info?part_no=C1608X5R1V475M080AC"
			(at 0 0 90)
			(layer "F.Fab")
			(hide yes)
			(effects
				(font
					(size 1.27 1.27)
					(thickness 0.15)
				)
			)
		)
		(property "Description" "SMD Multilayer Ceramic Capacitor, 4.7 µF, 35 V, 0603 [1608 Metric], ± 20%, X5R, C"
			(at 0 0 90)
			(layer "F.Fab")
			(hide yes)
			(effects
				(font
					(size 1.27 1.27)
					(thickness 0.15)
				)
			)
		)
		(property "Author" "Antmicro"
			(at 224.9 42.3 0)
			(layer "B.Fab")
			(hide yes)
			(effects
				(font
					(size 1 1)
					(thickness 0.15)
				)
				(justify mirror)
			)
		)
		(property "Dielectric" ""
			(at 224.9 42.3 0)
			(layer "B.Fab")
			(hide yes)
			(effects
				(font
					(size 1 1)
					(thickness 0.15)
				)
				(justify mirror)
			)
		)
		(property "License" "Apache-2.0"
			(at 224.9 42.3 0)
			(layer "B.Fab")
			(hide yes)
			(effects
				(font
					(size 1 1)
					(thickness 0.15)
				)
				(justify mirror)
			)
		)
		(property "MPN" "C1608X5R1V475M080AC"
			(at 224.9 42.3 0)
			(layer "B.Fab")
			(hide yes)
			(effects
				(font
					(size 1 1)
					(thickness 0.15)
				)
				(justify mirror)
			)
		)
		(property "Manufacturer" "TDK"
			(at 224.9 42.3 0)
			(layer "B.Fab")
			(hide yes)
			(effects
				(font
					(size 1 1)
					(thickness 0.15)
				)
				(justify mirror)
			)
		)
		(property "Val" "4u7"
			(at 224.9 42.3 0)
			(layer "B.Fab")
			(hide yes)
			(effects
				(font
					(size 1 1)
					(thickness 0.15)
				)
				(justify mirror)
			)
		)
		(property "Voltage" ""
			(at 224.9 42.3 0)
			(layer "B.Fab")
			(hide yes)
			(effects
				(font
					(size 1 1)
					(thickness 0.15)
				)
				(justify mirror)
			)
		)
		(property "DNP" ""
			(at 0 0 90)
			(unlocked yes)
			(layer "B.Fab")
			(hide yes)
			(effects
				(font
					(size 1 1)
					(thickness 0.15)
				)
				(justify mirror)
			)
		)
		(sheetname "/FPGA banks 13-16/")
		(sheetfile "fpga-banks-13-16.kicad_sch")
		(attr smd)
		(fp_line
			(start -0.15 -0.4)
			(end 0.15 -0.4)
			(stroke
				(width 0.15)
				(type solid)
			)
			(layer "B.SilkS")
		)
		(fp_line
			(start -0.15 0.4)
			(end 0.15 0.4)
			(stroke
				(width 0.15)
				(type solid)
			)
			(layer "B.SilkS")
		)
		(fp_rect
			(start -1.25 0.65)
			(end 1.25 -0.65)
			(stroke
				(width 0.05)
				(type solid)
			)
			(fill no)
			(layer "B.CrtYd")
		)
		(fp_rect
			(start -0.8 0.4)
			(end 0.8 -0.4)
			(stroke
				(width 0.15)
				(type solid)
			)
			(fill no)
			(layer "B.Fab")
		)
		(pad "1" smd roundrect
			(at -0.7 0 90)
			(size 0.8 1)
			(layers "B.Cu" "B.Mask" "B.Paste")
			(roundrect_rratio 0.2)
			(net 1 "GND")
			(pintype "passive")
		)
		(pad "2" smd roundrect
			(at 0.7 0 90)
			(size 0.8 1)
			(layers "B.Cu" "B.Mask" "B.Paste")
			(roundrect_rratio 0.2)
			(net 2 "VCC3V3")
			(pintype "passive")
		)
	)
	(footprint "antmicro-footprints:C_0603_1608Metric"
		(layer "B.Cu")
		(at 112.6 106.5 180)
		(descr "Capacitor SMD 0603")
		(tags "capacitor 0603")
		(property "Reference" "C105"
			(at -3.9 -0.3 0)
			(layer "B.SilkS")
			(effects
				(font
					(size 0.7 0.7)
					(thickness 0.15)
				)
				(justify left bottom mirror)
			)
		)
		(property "Value" "C_4u7_0603"
			(at 0 -1.6 0)
			(layer "B.Fab")
			(effects
				(font
					(size 0.7 0.7)
					(thickness 0.15)
				)
				(justify left bottom mirror)
			)
		)
		(property "Datasheet" "https://product.tdk.com/en/search/capacitor/ceramic/mlcc/info?part_no=C1608X5R1V475M080AC"
			(at 0 0 180)
			(layer "F.Fab")
			(hide yes)
			(effects
				(font
					(size 1.27 1.27)
					(thickness 0.15)
				)
			)
		)
		(property "Description" "SMD Multilayer Ceramic Capacitor, 4.7 µF, 35 V, 0603 [1608 Metric], ± 20%, X5R, C"
			(at 0 0 180)
			(layer "F.Fab")
			(hide yes)
			(effects
				(font
					(size 1.27 1.27)
					(thickness 0.15)
				)
			)
		)
		(property "Author" "Antmicro"
			(at 225.2 213 0)
			(layer "B.Fab")
			(hide yes)
			(effects
				(font
					(size 1 1)
					(thickness 0.15)
				)
				(justify mirror)
			)
		)
		(property "Dielectric" ""
			(at 225.2 213 0)
			(layer "B.Fab")
			(hide yes)
			(effects
				(font
					(size 1 1)
					(thickness 0.15)
				)
				(justify mirror)
			)
		)
		(property "License" "Apache-2.0"
			(at 225.2 213 0)
			(layer "B.Fab")
			(hide yes)
			(effects
				(font
					(size 1 1)
					(thickness 0.15)
				)
				(justify mirror)
			)
		)
		(property "MPN" "C1608X5R1V475M080AC"
			(at 225.2 213 0)
			(layer "B.Fab")
			(hide yes)
			(effects
				(font
					(size 1 1)
					(thickness 0.15)
				)
				(justify mirror)
			)
		)
		(property "Manufacturer" "TDK"
			(at 225.2 213 0)
			(layer "B.Fab")
			(hide yes)
			(effects
				(font
					(size 1 1)
					(thickness 0.15)
				)
				(justify mirror)
			)
		)
		(property "Val" "4u7"
			(at 225.2 213 0)
			(layer "B.Fab")
			(hide yes)
			(effects
				(font
					(size 1 1)
					(thickness 0.15)
				)
				(justify mirror)
			)
		)
		(property "Voltage" ""
			(at 225.2 213 0)
			(layer "B.Fab")
			(hide yes)
			(effects
				(font
					(size 1 1)
					(thickness 0.15)
				)
				(justify mirror)
			)
		)
		(sheetname "/FPGA banks 13-16/")
		(sheetfile "fpga-banks-13-16.kicad_sch")
		(attr smd)
		(fp_line
			(start -0.15 0.4)
			(end 0.15 0.4)
			(stroke
				(width 0.15)
				(type solid)
			)
			(layer "B.SilkS")
		)
		(fp_line
			(start -0.15 -0.4)
			(end 0.15 -0.4)
			(stroke
				(width 0.15)
				(type solid)
			)
			(layer "B.SilkS")
		)
		(fp_rect
			(start -1.25 0.65)
			(end 1.25 -0.65)
			(stroke
				(width 0.05)
				(type solid)
			)
			(fill no)
			(layer "B.CrtYd")
		)
		(fp_rect
			(start -0.8 0.4)
			(end 0.8 -0.4)
			(stroke
				(width 0.15)
				(type solid)
			)
			(fill no)
			(layer "B.Fab")
		)
		(pad "1" smd roundrect
			(at -0.7 0 180)
			(size 0.8 1)
			(layers "B.Cu" "B.Mask" "B.Paste")
			(roundrect_rratio 0.2)
			(net 1 "GND")
			(pintype "passive")
		)
		(pad "2" smd roundrect
			(at 0.7 0 180)
			(size 0.8 1)
			(layers "B.Cu" "B.Mask" "B.Paste")
			(roundrect_rratio 0.2)
			(net 2 "VCC3V3")
			(pintype "passive")
		)
	)
	(footprint "antmicro-footprints:C_0603_1608Metric"
		(layer "B.Cu")
		(at 114.4 129.8 180)
		(descr "Capacitor SMD 0603")
		(tags "capacitor 0603")
		(property "Reference" "C106"
			(at 1 -0.4 0)
			(layer "B.SilkS")
			(effects
				(font
					(size 0.7 0.7)
					(thickness 0.15)
				)
				(justify left bottom mirror)
			)
		)
		(property "Value" "C_4u7_0603"
			(at 0 -1.6 0)
			(layer "B.Fab")
			(effects
				(font
					(size 0.7 0.7)
					(thickness 0.15)
				)
				(justify left bottom mirror)
			)
		)
		(property "Datasheet" "https://product.tdk.com/en/search/capacitor/ceramic/mlcc/info?part_no=C1608X5R1V475M080AC"
			(at 0 0 180)
			(layer "F.Fab")
			(hide yes)
			(effects
				(font
					(size 1.27 1.27)
					(thickness 0.15)
				)
			)
		)
		(property "Description" "SMD Multilayer Ceramic Capacitor, 4.7 µF, 35 V, 0603 [1608 Metric], ± 20%, X5R, C"
			(at 0 0 180)
			(layer "F.Fab")
			(hide yes)
			(effects
				(font
					(size 1.27 1.27)
					(thickness 0.15)
				)
			)
		)
		(property "Author" "Antmicro"
			(at 228.8 259.6 0)
			(layer "B.Fab")
			(hide yes)
			(effects
				(font
					(size 1 1)
					(thickness 0.15)
				)
				(justify mirror)
			)
		)
		(property "Dielectric" ""
			(at 228.8 259.6 0)
			(layer "B.Fab")
			(hide yes)
			(effects
				(font
					(size 1 1)
					(thickness 0.15)
				)
				(justify mirror)
			)
		)
		(property "License" "Apache-2.0"
			(at 228.8 259.6 0)
			(layer "B.Fab")
			(hide yes)
			(effects
				(font
					(size 1 1)
					(thickness 0.15)
				)
				(justify mirror)
			)
		)
		(property "MPN" "C1608X5R1V475M080AC"
			(at 228.8 259.6 0)
			(layer "B.Fab")
			(hide yes)
			(effects
				(font
					(size 1 1)
					(thickness 0.15)
				)
				(justify mirror)
			)
		)
		(property "Manufacturer" "TDK"
			(at 228.8 259.6 0)
			(layer "B.Fab")
			(hide yes)
			(effects
				(font
					(size 1 1)
					(thickness 0.15)
				)
				(justify mirror)
			)
		)
		(property "Val" "4u7"
			(at 228.8 259.6 0)
			(layer "B.Fab")
			(hide yes)
			(effects
				(font
					(size 1 1)
					(thickness 0.15)
				)
				(justify mirror)
			)
		)
		(property "Voltage" ""
			(at 228.8 259.6 0)
			(layer "B.Fab")
			(hide yes)
			(effects
				(font
					(size 1 1)
					(thickness 0.15)
				)
				(justify mirror)
			)
		)
		(property "DNP" ""
			(at 0 0 180)
			(unlocked yes)
			(layer "B.Fab")
			(hide yes)
			(effects
				(font
					(size 1 1)
					(thickness 0.15)
				)
				(justify mirror)
			)
		)
		(sheetname "/FPGA banks 13-16/")
		(sheetfile "fpga-banks-13-16.kicad_sch")
		(attr smd)
		(fp_line
			(start -0.15 0.4)
			(end 0.15 0.4)
			(stroke
				(width 0.15)
				(type solid)
			)
			(layer "B.SilkS")
		)
		(fp_line
			(start -0.15 -0.4)
			(end 0.15 -0.4)
			(stroke
				(width 0.15)
				(type solid)
			)
			(layer "B.SilkS")
		)
		(fp_rect
			(start -1.25 0.65)
			(end 1.25 -0.65)
			(stroke
				(width 0.05)
				(type solid)
			)
			(fill no)
			(layer "B.CrtYd")
		)
		(fp_rect
			(start -0.8 0.4)
			(end 0.8 -0.4)
			(stroke
				(width 0.15)
				(type solid)
			)
			(fill no)
			(layer "B.Fab")
		)
		(pad "1" smd roundrect
			(at -0.7 0 180)
			(size 0.8 1)
			(layers "B.Cu" "B.Mask" "B.Paste")
			(roundrect_rratio 0.2)
			(net 1 "GND")
			(pintype "passive")
		)
		(pad "2" smd roundrect
			(at 0.7 0 180)
			(size 0.8 1)
			(layers "B.Cu" "B.Mask" "B.Paste")
			(roundrect_rratio 0.2)
			(net 2 "VCC3V3")
			(pintype "passive")
		)
	)
)
